(kicad_pcb
	(version 20260206)
	(generator "pcbnew")
	(generator_version "10.0")
	(general
		(thickness 1.6)
		(legacy_teardrops no)
	)
	(paper "A4")
	(title_block
		(title "01162023_DA0F0TEBIF0_F0T_Expander_BD_F_brd_V02_OCP.brd")
		(comment 1 "Grand Teton / footprints 4718-4723 of 9728")
	)
	(layers
		(0 "F.Cu" signal "TOP")
		(4 "In1.Cu" signal "GND")
		(6 "In2.Cu" signal "VCC")
		(8 "In3.Cu" signal "VCC1")
		(10 "In4.Cu" signal "GND1")
		(12 "In5.Cu" signal "IN1")
		(14 "In6.Cu" signal "GND2")
		(16 "In7.Cu" signal "IN2")
		(18 "In8.Cu" signal "GND3")
		(20 "In9.Cu" signal "IN3")
		(22 "In10.Cu" signal "GND4")
		(24 "In11.Cu" signal "IN4")
		(26 "In12.Cu" signal "GND5")
		(28 "In13.Cu" signal "IN5")
		(30 "In14.Cu" signal "GND6")
		(32 "In15.Cu" signal "IN6")
		(34 "In16.Cu" signal "GND7")
		(2 "B.Cu" signal "BOTTOM")
		(9 "F.Adhes" user "F.Adhesive")
		(11 "B.Adhes" user "B.Adhesive")
		(13 "F.Paste" user "Package Geometry/Pastemask Top")
		(15 "B.Paste" user "Package Geometry/Pastemask Bottom")
		(5 "F.SilkS" user "Ref Des/Silkscreen Top")
		(7 "B.SilkS" user "Ref Des/Silkscreen Bottom")
		(1 "F.Mask" user "Board Geometry/Soldermask Top")
		(3 "B.Mask" user "Board Geometry/Soldermask Bottom")
		(17 "Dwgs.User" user "User.Drawings")
		(19 "Cmts.User" user "User.Comments")
		(21 "Eco1.User" user "User.Eco1")
		(23 "Eco2.User" user "User.Eco2")
		(25 "Edge.Cuts" user "Board Geometry/Outline")
		(27 "Margin" user)
		(31 "F.CrtYd" user "Package Geometry/Place Bound Top")
		(29 "B.CrtYd" user "Package Geometry/Place Bound Bottom")
		(35 "F.Fab" user "Ref Des/Assembly Top")
		(33 "B.Fab" user "Ref Des/Assembly Bottom")
	)
	(footprint ""
		(layer "F.Cu")
		(at 454.896982 -115.646454 180)
		(property "Reference" "PR7059"
			(at 0 0 180)
			(layer "F.SilkS")
			(hide yes)
			(effects
				(font
					(size 1.27 1.27)
				)
			)
		)
		(property "Value" ""
			(at 0 0 180)
			(layer "F.Fab")
			(effects
				(font
					(size 1.27 1.27)
				)
			)
		)
		(duplicate_pad_numbers_are_jumpers no)
		(fp_line
			(start 0.7874 0.4064)
			(end -0.7874 0.4064)
			(stroke
				(width 0.1524)
				(type default)
			)
			(layer "F.SilkS")
		)
		(fp_line
			(start 0.7874 -0.4064)
			(end 0.7874 0.4064)
			(stroke
				(width 0.1524)
				(type default)
			)
			(layer "F.SilkS")
		)
		(fp_line
			(start -0.7874 0.4064)
			(end -0.7874 -0.4064)
			(stroke
				(width 0.1524)
				(type default)
			)
			(layer "F.SilkS")
		)
		(fp_line
			(start -0.7874 -0.4064)
			(end 0.7874 -0.4064)
			(stroke
				(width 0.1524)
				(type default)
			)
			(layer "F.SilkS")
		)
		(fp_line
			(start 0.67945 0.3048)
			(end 0.120396 0.3048)
			(stroke
				(width 0.1)
				(type default)
			)
			(layer "F.Fab")
		)
		(fp_line
			(start 0.67945 -0.3048)
			(end 0.67945 0.3048)
			(stroke
				(width 0.1)
				(type default)
			)
			(layer "F.Fab")
		)
		(fp_line
			(start 0.12065 -0.2794)
			(end 0.12065 -0.3048)
			(stroke
				(width 0.1)
				(type default)
			)
			(layer "F.Fab")
		)
		(fp_line
			(start 0.12065 -0.3048)
			(end 0.67945 -0.3048)
			(stroke
				(width 0.1)
				(type default)
			)
			(layer "F.Fab")
		)
		(fp_line
			(start 0.120396 0.3048)
			(end 0.120396 0.2794)
			(stroke
				(width 0.1)
				(type default)
			)
			(layer "F.Fab")
		)
		(fp_line
			(start 0.120396 0.2794)
			(end -0.12065 0.2794)
			(stroke
				(width 0.1)
				(type default)
			)
			(layer "F.Fab")
		)
		(fp_line
			(start -0.12065 0.3048)
			(end -0.67945 0.3048)
			(stroke
				(width 0.1)
				(type default)
			)
			(layer "F.Fab")
		)
		(fp_line
			(start -0.12065 0.2794)
			(end -0.12065 0.3048)
			(stroke
				(width 0.1)
				(type default)
			)
			(layer "F.Fab")
		)
		(fp_line
			(start -0.12065 -0.2794)
			(end 0.12065 -0.2794)
			(stroke
				(width 0.1)
				(type default)
			)
			(layer "F.Fab")
		)
		(fp_line
			(start -0.12065 -0.305054)
			(end -0.12065 -0.2794)
			(stroke
				(width 0.1)
				(type default)
			)
			(layer "F.Fab")
		)
		(fp_line
			(start -0.67945 0.3048)
			(end -0.67945 -0.305054)
			(stroke
				(width 0.1)
				(type default)
			)
			(layer "F.Fab")
		)
		(fp_line
			(start -0.67945 -0.305054)
			(end -0.12065 -0.305054)
			(stroke
				(width 0.1)
				(type default)
			)
			(layer "F.Fab")
		)
		(pad "1" smd circle
			(at -0.40005 0 180)
			(size 0 0)
			(layers "F.Cu" "F.Mask" "F.Paste")
			(net "P12V_NIC7_CO_OV_FB")
		)
		(pad "2" smd circle
			(at 0.40005 0 180)
			(size 0 0)
			(layers "F.Cu" "F.Mask" "F.Paste")
			(net "GND")
		)
	)
	(footprint ""
		(layer "F.Cu")
		(at 250.838716 -22.867366 90)
		(property "Reference" "C3933"
			(at 0 0 90)
			(layer "F.SilkS")
			(hide yes)
			(effects
				(font
					(size 1.27 1.27)
				)
			)
		)
		(property "Value" ""
			(at 0 0 90)
			(layer "F.Fab")
			(effects
				(font
					(size 1.27 1.27)
				)
			)
		)
		(duplicate_pad_numbers_are_jumpers no)
		(fp_line
			(start 0.7874 -0.4064)
			(end 0.7874 0.4064)
			(stroke
				(width 0.1524)
				(type default)
			)
			(layer "F.SilkS")
		)
		(fp_line
			(start -0.7874 -0.4064)
			(end 0.7874 -0.4064)
			(stroke
				(width 0.1524)
				(type default)
			)
			(layer "F.SilkS")
		)
		(fp_line
			(start 0.7874 0.4064)
			(end -0.7874 0.4064)
			(stroke
				(width 0.1524)
				(type default)
			)
			(layer "F.SilkS")
		)
		(fp_line
			(start -0.7874 0.4064)
			(end -0.7874 -0.4064)
			(stroke
				(width 0.1524)
				(type default)
			)
			(layer "F.SilkS")
		)
		(fp_line
			(start -0.12065 -0.305054)
			(end -0.12065 -0.2794)
			(stroke
				(width 0.1)
				(type default)
			)
			(layer "F.Fab")
		)
		(fp_line
			(start -0.67945 -0.305054)
			(end -0.12065 -0.305054)
			(stroke
				(width 0.1)
				(type default)
			)
			(layer "F.Fab")
		)
		(fp_line
			(start 0.67945 -0.3048)
			(end 0.67945 0.3048)
			(stroke
				(width 0.1)
				(type default)
			)
			(layer "F.Fab")
		)
		(fp_line
			(start 0.12065 -0.3048)
			(end 0.67945 -0.3048)
			(stroke
				(width 0.1)
				(type default)
			)
			(layer "F.Fab")
		)
		(fp_line
			(start 0.12065 -0.2794)
			(end 0.12065 -0.3048)
			(stroke
				(width 0.1)
				(type default)
			)
			(layer "F.Fab")
		)
		(fp_line
			(start -0.12065 -0.2794)
			(end 0.12065 -0.2794)
			(stroke
				(width 0.1)
				(type default)
			)
			(layer "F.Fab")
		)
		(fp_line
			(start 0.120396 0.2794)
			(end -0.12065 0.2794)
			(stroke
				(width 0.1)
				(type default)
			)
			(layer "F.Fab")
		)
		(fp_line
			(start -0.12065 0.2794)
			(end -0.12065 0.3048)
			(stroke
				(width 0.1)
				(type default)
			)
			(layer "F.Fab")
		)
		(fp_line
			(start 0.67945 0.3048)
			(end 0.120396 0.3048)
			(stroke
				(width 0.1)
				(type default)
			)
			(layer "F.Fab")
		)
		(fp_line
			(start 0.120396 0.3048)
			(end 0.120396 0.2794)
			(stroke
				(width 0.1)
				(type default)
			)
			(layer "F.Fab")
		)
		(fp_line
			(start -0.12065 0.3048)
			(end -0.67945 0.3048)
			(stroke
				(width 0.1)
				(type default)
			)
			(layer "F.Fab")
		)
		(fp_line
			(start -0.67945 0.3048)
			(end -0.67945 -0.305054)
			(stroke
				(width 0.1)
				(type default)
			)
			(layer "F.Fab")
		)
		(pad "1" smd circle
			(at -0.40005 0 90)
			(size 0 0)
			(layers "F.Cu" "F.Mask" "F.Paste")
			(net "P12V_SSD8")
		)
		(pad "2" smd circle
			(at 0.40005 0 90)
			(size 0 0)
			(layers "F.Cu" "F.Mask" "F.Paste")
			(net "GND")
		)
	)
	(footprint ""
		(layer "F.Cu")
		(at 102.402386 -284.834838 90)
		(property "Reference" "PC59"
			(at 0 0 90)
			(layer "F.SilkS")
			(hide yes)
			(effects
				(font
					(size 1.27 1.27)
				)
			)
		)
		(property "Value" ""
			(at 0 0 90)
			(layer "F.Fab")
			(effects
				(font
					(size 1.27 1.27)
				)
			)
		)
		(duplicate_pad_numbers_are_jumpers no)
		(fp_line
			(start 0.7874 -0.4064)
			(end 0.7874 0.4064)
			(stroke
				(width 0.1524)
				(type default)
			)
			(layer "F.SilkS")
		)
		(fp_line
			(start -0.7874 -0.4064)
			(end 0.7874 -0.4064)
			(stroke
				(width 0.1524)
				(type default)
			)
			(layer "F.SilkS")
		)
		(fp_line
			(start 0.7874 0.4064)
			(end -0.7874 0.4064)
			(stroke
				(width 0.1524)
				(type default)
			)
			(layer "F.SilkS")
		)
		(fp_line
			(start -0.7874 0.4064)
			(end -0.7874 -0.4064)
			(stroke
				(width 0.1524)
				(type default)
			)
			(layer "F.SilkS")
		)
		(fp_line
			(start -0.12065 -0.305054)
			(end -0.12065 -0.2794)
			(stroke
				(width 0.1)
				(type default)
			)
			(layer "F.Fab")
		)
		(fp_line
			(start -0.67945 -0.305054)
			(end -0.12065 -0.305054)
			(stroke
				(width 0.1)
				(type default)
			)
			(layer "F.Fab")
		)
		(fp_line
			(start 0.67945 -0.3048)
			(end 0.67945 0.3048)
			(stroke
				(width 0.1)
				(type default)
			)
			(layer "F.Fab")
		)
		(fp_line
			(start 0.12065 -0.3048)
			(end 0.67945 -0.3048)
			(stroke
				(width 0.1)
				(type default)
			)
			(layer "F.Fab")
		)
		(fp_line
			(start 0.12065 -0.2794)
			(end 0.12065 -0.3048)
			(stroke
				(width 0.1)
				(type default)
			)
			(layer "F.Fab")
		)
		(fp_line
			(start -0.12065 -0.2794)
			(end 0.12065 -0.2794)
			(stroke
				(width 0.1)
				(type default)
			)
			(layer "F.Fab")
		)
		(fp_line
			(start 0.120396 0.2794)
			(end -0.12065 0.2794)
			(stroke
				(width 0.1)
				(type default)
			)
			(layer "F.Fab")
		)
		(fp_line
			(start -0.12065 0.2794)
			(end -0.12065 0.3048)
			(stroke
				(width 0.1)
				(type default)
			)
			(layer "F.Fab")
		)
		(fp_line
			(start 0.67945 0.3048)
			(end 0.120396 0.3048)
			(stroke
				(width 0.1)
				(type default)
			)
			(layer "F.Fab")
		)
		(fp_line
			(start 0.120396 0.3048)
			(end 0.120396 0.2794)
			(stroke
				(width 0.1)
				(type default)
			)
			(layer "F.Fab")
		)
		(fp_line
			(start -0.12065 0.3048)
			(end -0.67945 0.3048)
			(stroke
				(width 0.1)
				(type default)
			)
			(layer "F.Fab")
		)
		(fp_line
			(start -0.67945 0.3048)
			(end -0.67945 -0.305054)
			(stroke
				(width 0.1)
				(type default)
			)
			(layer "F.Fab")
		)
		(pad "1" smd circle
			(at -0.40005 0 90)
			(size 0 0)
			(layers "F.Cu" "F.Mask" "F.Paste")
			(net "SW_P12V_P0V8_PEX0_FLT")
		)
		(pad "2" smd circle
			(at 0.40005 0 90)
			(size 0 0)
			(layers "F.Cu" "F.Mask" "F.Paste")
			(net "GND")
		)
	)
	(footprint ""
		(layer "F.Cu")
		(at 355.727 -183.388)
		(property "Reference" "R4747"
			(at 0 0 0)
			(layer "F.SilkS")
			(hide yes)
			(effects
				(font
					(size 1.27 1.27)
				)
			)
		)
		(property "Value" ""
			(at 0 0 0)
			(layer "F.Fab")
			(effects
				(font
					(size 1.27 1.27)
				)
			)
		)
		(duplicate_pad_numbers_are_jumpers no)
		(fp_line
			(start -0.7874 -0.4064)
			(end 0.7874 -0.4064)
			(stroke
				(width 0.1524)
				(type default)
			)
			(layer "F.SilkS")
		)
		(fp_line
			(start -0.7874 0.4064)
			(end -0.7874 -0.4064)
			(stroke
				(width 0.1524)
				(type default)
			)
			(layer "F.SilkS")
		)
		(fp_line
			(start 0.7874 -0.4064)
			(end 0.7874 0.4064)
			(stroke
				(width 0.1524)
				(type default)
			)
			(layer "F.SilkS")
		)
		(fp_line
			(start 0.7874 0.4064)
			(end -0.7874 0.4064)
			(stroke
				(width 0.1524)
				(type default)
			)
			(layer "F.SilkS")
		)
		(fp_line
			(start -0.67945 -0.305054)
			(end -0.12065 -0.305054)
			(stroke
				(width 0.1)
				(type default)
			)
			(layer "F.Fab")
		)
		(fp_line
			(start -0.67945 0.3048)
			(end -0.67945 -0.305054)
			(stroke
				(width 0.1)
				(type default)
			)
			(layer "F.Fab")
		)
		(fp_line
			(start -0.12065 -0.305054)
			(end -0.12065 -0.2794)
			(stroke
				(width 0.1)
				(type default)
			)
			(layer "F.Fab")
		)
		(fp_line
			(start -0.12065 -0.2794)
			(end 0.12065 -0.2794)
			(stroke
				(width 0.1)
				(type default)
			)
			(layer "F.Fab")
		)
		(fp_line
			(start -0.12065 0.2794)
			(end -0.12065 0.3048)
			(stroke
				(width 0.1)
				(type default)
			)
			(layer "F.Fab")
		)
		(fp_line
			(start -0.12065 0.3048)
			(end -0.67945 0.3048)
			(stroke
				(width 0.1)
				(type default)
			)
			(layer "F.Fab")
		)
		(fp_line
			(start 0.120396 0.2794)
			(end -0.12065 0.2794)
			(stroke
				(width 0.1)
				(type default)
			)
			(layer "F.Fab")
		)
		(fp_line
			(start 0.120396 0.3048)
			(end 0.120396 0.2794)
			(stroke
				(width 0.1)
				(type default)
			)
			(layer "F.Fab")
		)
		(fp_line
			(start 0.12065 -0.3048)
			(end 0.67945 -0.3048)
			(stroke
				(width 0.1)
				(type default)
			)
			(layer "F.Fab")
		)
		(fp_line
			(start 0.12065 -0.2794)
			(end 0.12065 -0.3048)
			(stroke
				(width 0.1)
				(type default)
			)
			(layer "F.Fab")
		)
		(fp_line
			(start 0.67945 -0.3048)
			(end 0.67945 0.3048)
			(stroke
				(width 0.1)
				(type default)
			)
			(layer "F.Fab")
		)
		(fp_line
			(start 0.67945 0.3048)
			(end 0.120396 0.3048)
			(stroke
				(width 0.1)
				(type default)
			)
			(layer "F.Fab")
		)
		(pad "1" smd circle
			(at -0.40005 0)
			(size 0 0)
			(layers "F.Cu" "F.Mask" "F.Paste")
			(net "PCA9555_0_PEX2_A0")
		)
		(pad "2" smd circle
			(at 0.40005 0)
			(size 0 0)
			(layers "F.Cu" "F.Mask" "F.Paste")
			(net "P3V3_AUX")
		)
	)
	(footprint ""
		(layer "F.Cu")
		(at 268.53515 -78.885796)
		(property "Reference" "R1050"
			(at 0 0 0)
			(layer "F.SilkS")
			(hide yes)
			(effects
				(font
					(size 1.27 1.27)
				)
			)
		)
		(property "Value" ""
			(at 0 0 0)
			(layer "F.Fab")
			(effects
				(font
					(size 1.27 1.27)
				)
			)
		)
		(duplicate_pad_numbers_are_jumpers no)
		(fp_line
			(start -0.7874 -0.4064)
			(end 0.7874 -0.4064)
			(stroke
				(width 0.1524)
				(type default)
			)
			(layer "F.SilkS")
		)
		(fp_line
			(start -0.7874 0.4064)
			(end -0.7874 -0.4064)
			(stroke
				(width 0.1524)
				(type default)
			)
			(layer "F.SilkS")
		)
		(fp_line
			(start 0.7874 -0.4064)
			(end 0.7874 0.4064)
			(stroke
				(width 0.1524)
				(type default)
			)
			(layer "F.SilkS")
		)
		(fp_line
			(start 0.7874 0.4064)
			(end -0.7874 0.4064)
			(stroke
				(width 0.1524)
				(type default)
			)
			(layer "F.SilkS")
		)
		(fp_line
			(start -0.67945 -0.305054)
			(end -0.12065 -0.305054)
			(stroke
				(width 0.1)
				(type default)
			)
			(layer "F.Fab")
		)
		(fp_line
			(start -0.67945 0.3048)
			(end -0.67945 -0.305054)
			(stroke
				(width 0.1)
				(type default)
			)
			(layer "F.Fab")
		)
		(fp_line
			(start -0.12065 -0.305054)
			(end -0.12065 -0.2794)
			(stroke
				(width 0.1)
				(type default)
			)
			(layer "F.Fab")
		)
		(fp_line
			(start -0.12065 -0.2794)
			(end 0.12065 -0.2794)
			(stroke
				(width 0.1)
				(type default)
			)
			(layer "F.Fab")
		)
		(fp_line
			(start -0.12065 0.2794)
			(end -0.12065 0.3048)
			(stroke
				(width 0.1)
				(type default)
			)
			(layer "F.Fab")
		)
		(fp_line
			(start -0.12065 0.3048)
			(end -0.67945 0.3048)
			(stroke
				(width 0.1)
				(type default)
			)
			(layer "F.Fab")
		)
		(fp_line
			(start 0.120396 0.2794)
			(end -0.12065 0.2794)
			(stroke
				(width 0.1)
				(type default)
			)
			(layer "F.Fab")
		)
		(fp_line
			(start 0.120396 0.3048)
			(end 0.120396 0.2794)
			(stroke
				(width 0.1)
				(type default)
			)
			(layer "F.Fab")
		)
		(fp_line
			(start 0.12065 -0.3048)
			(end 0.67945 -0.3048)
			(stroke
				(width 0.1)
				(type default)
			)
			(layer "F.Fab")
		)
		(fp_line
			(start 0.12065 -0.2794)
			(end 0.12065 -0.3048)
			(stroke
				(width 0.1)
				(type default)
			)
			(layer "F.Fab")
		)
		(fp_line
			(start 0.67945 -0.3048)
			(end 0.67945 0.3048)
			(stroke
				(width 0.1)
				(type default)
			)
			(layer "F.Fab")
		)
		(fp_line
			(start 0.67945 0.3048)
			(end 0.120396 0.3048)
			(stroke
				(width 0.1)
				(type default)
			)
			(layer "F.Fab")
		)
		(pad "1" smd circle
			(at -0.40005 0)
			(size 0 0)
			(layers "F.Cu" "F.Mask" "F.Paste")
			(net "CLK_BUFFER_9ZXL0851E_0_7_OE1_N")
		)
		(pad "2" smd circle
			(at 0.40005 0)
			(size 0 0)
			(layers "F.Cu" "F.Mask" "F.Paste")
			(net "P3V3")
		)
	)
	(footprint ""
		(layer "F.Cu")
		(at 268.461236 -367.527586 -90)
		(property "Reference" "PQ6606"
			(at -1.826768 -3.552952 0)
			(unlocked yes)
			(layer "F.SilkS")
			(effects
				(font
					(size 0.7874 0.5842)
					(thickness 0.1524)
				)
				(justify left)
			)
		)
		(property "Value" ""
			(at 0 0 270)
			(layer "F.Fab")
			(effects
				(font
					(size 1.27 1.27)
				)
			)
		)
		(duplicate_pad_numbers_are_jumpers no)
		(fp_line
			(start -1.584198 1.53416)
			(end -1.584198 -1.53416)
			(stroke
				(width 0.1524)
				(type default)
			)
			(layer "F.SilkS")
		)
		(fp_line
			(start 1.584198 1.53416)
			(end -1.584198 1.53416)
			(stroke
				(width 0.1524)
				(type default)
			)
			(layer "F.SilkS")
		)
		(fp_line
			(start -1.584198 -1.53416)
			(end 1.584198 -1.53416)
			(stroke
				(width 0.1524)
				(type default)
			)
			(layer "F.SilkS")
		)
		(fp_line
			(start 1.584198 -1.53416)
			(end 1.584198 1.53416)
			(stroke
				(width 0.1524)
				(type default)
			)
			(layer "F.SilkS")
		)
		(fp_line
			(start -0.700024 1.500124)
			(end -0.700024 -1.500124)
			(stroke
				(width 0.1)
				(type default)
			)
			(layer "F.Fab")
		)
		(fp_line
			(start 0.700024 1.500124)
			(end -0.700024 1.500124)
			(stroke
				(width 0.1)
				(type default)
			)
			(layer "F.Fab")
		)
		(fp_line
			(start -0.700024 -1.500124)
			(end 0.700024 -1.500124)
			(stroke
				(width 0.1)
				(type default)
			)
			(layer "F.Fab")
		)
		(fp_line
			(start 0.700024 -1.500124)
			(end 0.700024 1.500124)
			(stroke
				(width 0.1)
				(type default)
			)
			(layer "F.Fab")
		)
		(pad "B" smd rect
			(at -0.999998 -0.94996)
			(size 0.8128 0.9144)
			(layers "F.Cu" "F.Mask" "F.Paste")
			(net "LTC4282_TEMP_R_D+")
		)
		(pad "C" smd rect
			(at 0.999998 0)
			(size 0.8128 0.9144)
			(layers "F.Cu" "F.Mask" "F.Paste")
			(net "LTC4282_TEMP_R_D+")
		)
		(pad "E" smd rect
			(at -0.999998 0.94996)
			(size 0.8128 0.9144)
			(layers "F.Cu" "F.Mask" "F.Paste")
			(net "LTC4282_TEMP_R_D-")
		)
	)
)
